# BASEBOARD_FAB2 (Tioga Pass) — schematic parts with pin connectivity, parts 3292–3453 of 4751; source: Cadence DE-HDL packaged netlist (pstxprt.dat, pstxnet.dat, pstchip.dat)

R4D58  RES  1.00K 1% CHIP  pkg 0402  page 201 : 1 = P3V3_STBY ; 2 = VR_VRRDY_PVCCIN_CPU0
R4D60  RES  100.0K 1% CHIP  pkg 0402  page 213 : 1 = VR_FET_SW_P12V_STBY_PVCCIN_CPU0 ; 2 = VR_PVCCIO_CPU1_VINSEN
R4D63  RES  22.1 1.0% CHIP  pkg 0402  page 201 : 1 = VR_VRRDY_PVCCIN_CPU0 ; 2 = PWRGD_PVCCIN_CPU0
R4D64  RES  3.16K 1% CHIP  pkg 0402  page 213 : 1 = VR_PVCCIO_CPU1_XADDR1 ; 2 = GND
R4D65  RES  33.2 1% CHIP  pkg 0402  page 201 : 1 = PWRGD_PVSA_CPU0_R ; 2 = PWRGD_PVSA_CPU0
R4D66  RES  0.0 5% CHIP  pkg 0402  page 201 : 1 = SVID_VDIO_PVCCIN_CPU0 ; 2 = SVID_DIO0_CPU0_R
R4D67  RES  0.0 5% CHIP  pkg 0402  page 201 : 1 = SVID_VALERT_VCCIN_CPU0 ; 2 = SVID_ALERT0_CPU0_R_N
R4D68  RES  68.1K 1% EMPTY  pkg 0402  page 204 : 1 = VR_PVCCIN_CPU0_PH5_OCSET ; 2 = GND
R4D69  RES  4.75K 1% CHIP  pkg 0402  page 102 : 1 = P3V3 ; 2 = FM_CPU1_MCP_CLK_EN_N
R4D70  RES  4.75K 1% CHIP  pkg 0402  page 102 : 1 = P3V3 ; 2 = FM_CPU0_MCP_CLK_EN_N
R4D71  RES  68.1K 1% EMPTY  pkg 0402  page 203 : 1 = VR_PVCCIN_CPU0_PH4_OCSET ; 2 = GND
R4D72  RES  68.1K 1% EMPTY  pkg 0402  page 203 : 1 = VR_PVCCIN_CPU0_PH3_OCSET ; 2 = GND
R4E2  RES  3.16K 1% CHIP  pkg 0402  page 213 : 1 = VR_PVCCIO_CPU1_XADDR2 ; 2 = GND
R4E3  RES  1.00K 1% CHIP  pkg 0402  page 201 : 1 = P3V3_STBY ; 2 = IRQ_PVCCIN_CPU0_VRHOT_LVC3_R_N
R4E4  RES  1.00K 1% CHIP  pkg 0402  page 201 : 1 = P3V3_STBY ; 2 = FM_PVCCIN_CPU0_PWR_IN_ALERT_N
R4E5  RES  1.00K 1% CHIP  pkg 0402  page 201 : 1 = P3V3_STBY ; 2 = PWRGD_PVSA_CPU0_R
R4E6  RES  150.0 1% CHIP  pkg 0402  page 201 : 1 = SVID_CLK0_CPU0_R ; 2 = SVID_VCLK_PVCCIN_CPU0
R4E7  RES  10.0 1% CHIP  pkg 0402  page 213 : 1 = VSENSE_PVCCIO_CPU1_AVSP ; 2 = VR_PVCCIO_CPU1_AVSP
R4E8  RES  10.0 1% CHIP  pkg 0402  page 201 : 1 = VSENSE_PVCCIN_CPU0_P ; 2 = VSENSE_PVCCIN_CPU0_AVSP
R4E9  RES  49.9 1% EMPTY  pkg 0402  page 201 : 1 = PVCCIO_CPU0 ; 2 = SVID_CLK0_CPU0_R
R4E10  RES  100.0 1% EMPTY  pkg 0402  page 201 : 1 = PVCCIO_CPU0 ; 2 = SVID_DIO0_CPU0_R
R4E13  RES  100.0 1% CHIP  pkg 0603  page 203 : 1 = PVCCIN_CPU0 ; 2 = GND
R4E14  RES  100.0 1% CHIP  pkg 0402  page 204 : 1 = VSENSE_PVCCIN_CPU0_P ; 2 = PVCCIN_CPU0
R4E15  RES  1.00K 1% EMPTY  pkg 0402  page 204 : 1 = VSENSE_PVCCIN_CPU0_P ; 2 = VSENSE_PVCCIN_CPU0_N
R4E16  RES  0.0 5% CHIP  pkg 0402  page 204 : 1 = VSENSE_PVCCIN_CPU0_P ; 2 = VSENSE_PVCCIN_CPU0_SKT_VSEN
R4E17  RES  0.0 5% CHIP  pkg 0402  page 204 : 1 = VSENSE_PVCCIN_CPU0_N ; 2 = VSENSE_PVCCIN_CPU0_SKT_VRTN
R4E18  RES  100.0 1% CHIP  pkg 0402  page 204 : 1 = VSENSE_PVCCIN_CPU0_N ; 2 = GND
R4E19  RES  68.1K 1% EMPTY  pkg 0402  page 202 : 1 = VR_PVCCIN_CPU0_PH2_OCSET ; 2 = GND
R4E20  RES  2.26K 1.0% EMPTY  pkg 0402  page 201 : 1 = P3V3_STBY ; 2 = PU_VR_PVCCIN_CPU0_FLT1_SMBALT_N
R4E21  RES  68.1K 1% EMPTY  pkg 0402  page 214 : 1 = VR_PVCCIO_CPU1_OCSET ; 2 = GND
R4E22  RES  68.1K 1% EMPTY  pkg 0402  page 202 : 1 = VR_PVCCIN_CPU0_PH1_OCSET ; 2 = GND
R4F2  RES  0.002 1% CHIP  pkg 1206  page 197 : 1 = P12V_STBY ; 2 = P12V_NVDIMM_ABC
R4F3  RES  2 1.0% CHIP  pkg 0402  page 98 : 1 = M_A_CPU_VREF ; 2 = M_A_VREF
R4F4  RES  1.00K 1% CHIP  pkg 0402  page 98 : 1 = PVDDQ_ABC ; 2 = M_A_VREF
R4F5  RES  1.00K 1% CHIP  pkg 0402  page 98 : 1 = M_A_VREF ; 2 = GND
R4F6  RES  2.2 5% EMPTY  pkg 0402  page 233 : 1 = VR_PVPP_GHJ_SNUB ; 2 = GND
R4G1  RES  2 1.0% CHIP  pkg 0402  page 98 : 1 = M_B_CPU_VREF ; 2 = M_B_VREF
R4G2  RES  1.00K 1% CHIP  pkg 0402  page 98 : 1 = PVDDQ_ABC ; 2 = M_B_VREF
R4G3  RES  1.00K 1% CHIP  pkg 0402  page 98 : 1 = M_B_VREF ; 2 = GND
R4G4  RES  0.0 5% CHIP  pkg 0402  page 233 : 1 = FM_PVPP_CPU1_EN ; 2 = FM_PVPP_PVDDQ_CPU1_EN_GHJ
R4G5  RES  10.0K 1% CHIP  pkg 0402  page 233 : 1 = FM_PVPP_CPU1_EN ; 2 = GND
R4G6  RES  120.0 1% CHIP  pkg 0603  page 233 : 1 = PVPP_GHJ ; 2 = GND
R4G7  RES  20.0K 1% CHIP  pkg 0402  page 233 : 1 = VSENSE_PVPP_GHJ ; 2 = VR_FB_PVPP_GHJ
R4G8  RES  0.0 5% CHIP  pkg 0402  page 233 : 1 = PVPP_GHJ ; 2 = VSENSE_PVPP_GHJ
R4G9  RES  6.19K 1% CHIP  pkg 0402  page 233 : 1 = VR_FB_PVPP_GHJ ; 2 = AGND_PVPP_GHJ
R4G10  RES  1.0K 0.1% CHIP  pkg 0402  page 233 : 1 = VSENSE_PVPP_GHJ ; 2 = VR_COMP_PVPP_GHJ
R4G11  RES  7.87K 1.0% CHIP  pkg 0402  page 233 : 1 = VR_PVPP_GHJ_ISET ; 2 = AGND_PVPP_GHJ
R4G12  RES  22.1 1.0% CHIP  pkg 0402  page 233 : 1 = PWRGD_PVPP_GHJ_R ; 2 = PWRGD_PVPP_GHJ
R4G13  RES  7.87K 1.0% CHIP  pkg 0402  page 233 : 1 = VR_COMP_RC_PVPP_GHJ ; 2 = VR_FB_PVPP_GHJ
R4G14  RES  1.00K 1% CHIP  pkg 0402  page 233 : 1 = P3V3_STBY ; 2 = PWRGD_PVPP_GHJ_R
R4G15  RES  33.2 1% CHIP  pkg 0402  page 229 : 1 = PWRGD_PVTT_GHJ_CPU1_R ; 2 = PWRGD_PVTT_CPU1
R4G16  RES  0.0 5% CHIP  pkg 0402  page 229 : 1 = PWRGD_PVDDQ_GHJ_R ; 2 = FM_PVTT_GHJ_EN_R
R4G17  RES  10.0K 1% CHIP  pkg 0402  page 229 : 1 = P3V3 ; 2 = PWRGD_PVTT_GHJ_CPU1_R
R4G18  RES  10.0K 1% CHIP  pkg 0402  page 221 : 1 = P3V3 ; 2 = PWRGD_PVTT_ABC_CPU0_R
R4G19  RES  33.2 1% CHIP  pkg 0402  page 221 : 1 = PWRGD_PVTT_ABC_CPU0_R ; 2 = PWRGD_PVTT_CPU0
R4G20  RES  2 1.0% CHIP  pkg 0402  page 98 : 1 = M_C_CPU_VREF ; 2 = M_C_VREF
R4G21  RES  1.00K 1% CHIP  pkg 0402  page 98 : 1 = PVDDQ_ABC ; 2 = M_C_VREF
R4G22  RES  1.00K 1% CHIP  pkg 0402  page 98 : 1 = M_C_VREF ; 2 = GND
R4G23  RES  0.0 5% CHIP  pkg 0402  page 221 : 1 = PWRGD_PVDDQ_ABC_R ; 2 = FM_PVTT_ABC_EN_R
R4G24  RES  0 5.0% CHIP  pkg 0603  page 233 : 1 = VR_PVPP_GHJ_BOOT ; 2 = VR_PVPP_GHJ_BOOT_R
R4G25  RES  0.0 5% CHIP  pkg 0402  page 233 : 1 = GND ; 2 = AGND_PVPP_GHJ
R4L2  RES  100.0 1% EMPTY  pkg 0402  page 220 : 1 = VSENSE_PVDDQ_DEF_P ; 2 = VSENSE_PVDDQ_DEF_N
R4L4  RES  120.0 1% CHIP  pkg 0603  page 220 : 1 = PVDDQ_DEF ; 2 = GND
R4P1  RES  240 1.0% EMPTY  pkg 0402  page 90 : 1 = GND ; 2 = PD_CPU0_BIST_ENABLE
R4P2  RES  49.9 1% CHIP  pkg 0402  page 21 : 1 = A_CPU0_PE3_RBIAS ; 2 = GND
R4P3  RES  49.9 1% CHIP  pkg 0402  page 21 : 1 = A_CPU0_PE012_RBIAS ; 2 = GND
R4P4  RES  49.9 1% CHIP  pkg 0402  page 21 : 1 = A_CPU0_UPI2_RBIAS ; 2 = GND
R4P5  RES  10.0K 1% CHIP  pkg 0402  page 97 : 1 = GND ; 2 = PD_CPU0_MCP01_DMON
R4P6  RES  240 1.0% EMPTY  pkg 0402  page 90 : 1 = GND ; 2 = PD_CPU0_DMIMODE_OVERRIDE
R4P7  RES  240 1.0% EMPTY  pkg 0402  page 90 : 1 = GND ; 2 = PD_CPU0_KSFC_DIS
R4P8  RES  90.9 1% CHIP  pkg 0402  page 21 : 1 = A_CPU0_ABC_RCOMP0 ; 2 = GND
R4P10  RES  90.9 1% CHIP  pkg 0402  page 21 : 1 = A_CPU0_ABC_RCOMP1 ; 2 = GND
R4P11  RES  100.0 1% CHIP  pkg 0402  page 21 : 1 = A_CPU0_ABC_RCOMP2 ; 2 = GND
R4P12  RES  100.0 1% CHIP  pkg 0402  page 112 : 1 = PVCCIO_CPU0 ; 2 = XDP_CPU_MBP0_N
R4P14  RES  240 1.0% CHIP  pkg 0402  page 90 : 1 = PVCCIO_CPU0 ; 2 = PU_CPU0_LEGACY_SKT
R4P15  RES  100.0 1% CHIP  pkg 0402  page 112 : 1 = PVCCIO_CPU0 ; 2 = XDP_CPU_MBP1_N
R4P17  RES  150.0 1% CHIP  pkg 0402  page 152 : 1 = H_CPU0_MEMABC_MEMHOT_G_N ; 2 = PVCCIO_CPU0
R4P18  RES  49.9 1% CHIP  pkg 0402  page 21 : 1 = H_PM_SYNC_GTL_R1 ; 2 = H_PM_SYNC_GTL
R4P19  RES  49.9 1% CHIP  pkg 0402  page 21 : 1 = H_PMSYNC_CLK_24M_CPU0 ; 2 = H_PMSYNC_CLK_24M
R4P20  RES  150.0 1% CHIP  pkg 0402  page 152 : 1 = H_CPU0_MEMDEF_MEMHOT_G_N ; 2 = PVCCIO_CPU0
R4P21  RES  240 1.0% CHIP  pkg 0402  page 97 : 1 = PVCCIO_CPU0 ; 2 = PU_CPU0_TSC_SYNC
R4P23  RES  150.0 1% CHIP  pkg 0402  page 112 : 1 = PVCCIO_CPU0 ; 2 = XDP_CPU0_TDO
R4P24  RES  150.0 1% CHIP  pkg 0402  page 112 : 1 = PVCCIO_CPU0 ; 2 = XDP_CPU_TDI
R4R1  RES  1.00K 1% CHIP  pkg 0402  page 157 : 1 = H_CPU0_FAST_WAKE_N ; 2 = H_CPU0_FAST_WAKE_B_N
R4R2  RES  150.0 1% CHIP  pkg 0402  page 92 : 1 = PVCCIO_CPU0 ; 2 = H_CPU0_CATERR_G_N
R4R3  RES  150.0 1% CHIP  pkg 0402  page 93 : 1 = PVCCIO_CPU0 ; 2 = H_CPU0_PROCHOT_G_N
R4R4  RES  150.0 1% CHIP  pkg 0402  page 97 : 1 = PVCCIO_CPU0 ; 2 = H_CPU0_FAST_WAKE_N
R4R5  RES  4.75K 1% CHIP  pkg 0402  page 21 : 1 = P3V3_STBY ; 2 = FM_CPU0_SKTOCC_LVT3_N
R4R6  RES  1.00K 1% CHIP  pkg 0402  page 113 : 1 = JTAG_MCP_CPU0_TDI_R ; 2 = JTAG_MCP_CPU0_TDI
R4T1  RES  0.0 5% CHIP  pkg 0402  page 89 : 1 = FM_ADR_COMPLETE_DLY ; 2 = FM_ADR_COMPLETE_R
R4T2  RES  0.0 5% EMPTY  pkg 0402  page 89 : 1 = FM_ADR_COMPLETE ; 2 = FM_ADR_COMPLETE_R
R4T3  RES  10.0 1% CHIP  pkg 0402  page 99 : 1 = SMB_DDR_ABC_SCL_G_R ; 2 = SMB_DDR_ABC_SCL_G
R4T4  RES  10.0 1% CHIP  pkg 0402  page 99 : 1 = SMB_DDR_ABC_SDA_G_R ; 2 = SMB_DDR_ABC_SDA_G
R4T5  RES  240 1.0% CHIP  pkg 0402  page 99 : 1 = PVCCIO_CPU0 ; 2 = SMB_DDR_ABC_SCL_G
R4T6  RES  240 1.0% CHIP  pkg 0402  page 99 : 1 = PVCCIO_CPU0 ; 2 = SMB_DDR_ABC_SDA_G
R4T7  RES  665 1.0% CHIP  pkg 0402  page 99 : 1 = PVPP_ABC ; 2 = SMB_DDR_ABC_VPP_SCL_R
R4T8  RES  665 1.0% CHIP  pkg 0402  page 99 : 1 = PVPP_ABC ; 2 = SMB_DDR_ABC_VPP_SDA_R
R4T9  RES  20.0 1% CHIP  pkg 0402  page 99 : 1 = SMB_DDR_ABC_VPP_SCL_R ; 2 = SMB_DDR_ABC_VPP_SCL
R4T10  RES  20.0 1% CHIP  pkg 0402  page 99 : 1 = SMB_DDR_ABC_VPP_SDA_R ; 2 = SMB_DDR_ABC_VPP_SDA
R4U1  RES  4.75K 1% CHIP  pkg 0402  page 94 : 1 = P3V3_STBY ; 2 = FM_MEM_THERM_EVENT_LVT3_N
R4U2  RES  2.21K 1% CHIP  pkg 0402  page 94 : 1 = PVPP_ABC ; 2 = FM_DIMM_EVENT_COD_N
R4U3  RES  4.75K 1% CHIP  pkg 0402  page 94 : 1 = PVPP_ABC ; 2 = FM_DIMM_EVENT_FET
R4U4  RES  33.0K 5% CHIP  pkg 0402  page 94 : 1 = FM_DIMM_EVENT_FET ; 2 = GND
R4U6  RES  100.0 1% EMPTY  pkg 0402  page 217 : 1 = VSENSE_PVDDQ_ABC_P ; 2 = VSENSE_PVDDQ_ABC_N
R4W1  RES  4.75K 1% CHIP  pkg 0402  page 191 : 1 = P3V3_STBY ; 2 = PU_CPLD1_PT20D_PROGRAMN
R4W2  RES  1.00K 1% CHIP  pkg 0402  page 102 : 1 = P3V3_DB1200 ; 2 = P3V3_DB1200_R1
R4W3  RES  3.3K 5% CHIP  pkg 0402  page 102 : 1 = P3V3_DB1200 ; 2 = SMB_HOST_STBY_LVC3_SDA_R2
R4W4  RES  3.3K 5% CHIP  pkg 0402  page 102 : 1 = P3V3_DB1200 ; 2 = SMB_HOST_STBY_LVC3_SCL_R2
R4W5  RES  0.0 5% EMPTY  pkg 0402  page 102 : 1 = FM_DB1200_PWRGD ; 2 = FM_DB1200_PWRGD_R
R4W6  RES  4.75K 1% CHIP  pkg 0402  page 102 : 1 = P3V3_DB1200 ; 2 = FM_DB1200_PWRGD_R
R5D1  RES  90.9 1% CHIP  pkg 0402  page 21 : 1 = A_CPU0_DEF_RCOMP0 ; 2 = GND
R5D2  RES  90.9 1% CHIP  pkg 0402  page 21 : 1 = A_CPU0_DEF_RCOMP1 ; 2 = GND
R5D3  RES  240 1.0% CHIP  pkg 0402  page 90 : 1 = PVCCIO_CPU0 ; 2 = PU_CPU0_FRMAGENT
R5D4  RES  240 1.0% CHIP  pkg 0402  page 90 : 1 = PVCCIO_CPU0 ; 2 = PU_CPU0_TXT_AGENT
R5D5  RES  249 0.1% CHIP  pkg 0402  page 37 : 1 = VSENSE_PMAX_CPU0 ; 2 = GND
R5D6  RES  10.0 1% EMPTY  pkg 0402  page 37 : 1 = PVCCIO_CPU0 ; 2 = VSENSE_PMAX_CPU0
R5N1  RES  10.0K 1% CHIP  pkg 0402  page 21 : 1 = P3V3_STBY ; 2 = FM_CPU0_PKGID0
R5N2  RES  1.8K 1% CHIP  pkg 0402  page 21 : 1 = P3V3_STBY ; 2 = FM_CPU0_PROC_ID1
R5N3  RES  10.0K 1% CHIP  pkg 0402  page 21 : 1 = P3V3_STBY ; 2 = FM_CPU0_PKGID2
R5N4  RES  1.8K 1% CHIP  pkg 0402  page 21 : 1 = P3V3_STBY ; 2 = FM_CPU0_PROC_ID0
R5N5  RES  10.0K 1% CHIP  pkg 0402  page 21 : 1 = P3V3_STBY ; 2 = FM_CPU0_PKGID1
R5P1  RES  100.0K 1% CHIP  pkg 0603  page 37 : 1 = PVCCIN_CPU0 ; 2 = VSENSE_VCCINR2PMAX_CPU0
R5P2  RES  49.9 1% CHIP  pkg 0402  page 90 : 1 = PD_CPU0_TEST14 ; 2 = GND
R5P3  RES  49.9 1% CHIP  pkg 0402  page 90 : 1 = PD_CPU0_TEST13 ; 2 = GND
R5P4  RES  49.9 1% CHIP  pkg 0402  page 22 : 1 = PD_CPU0_RSVD_TEST_2 ; 2 = GND
R5R1  RES  49.9 1% CHIP  pkg 0402  page 22 : 1 = PD_CPU0_RSVD_TEST_1 ; 2 = GND
R5W1  RES  0.0 5% CHIP  pkg 0402  page 113 : 1 = P1V8_MCP_CPU0 ; 2 = JTAG_MCP_CPU0_TDI_R
R5W2  RES  0.0 5% CHIP  pkg 0402  page 113 : 1 = P1V8_MCP_CPU1 ; 2 = JTAG_MCP_CPU1_TDI_R
R6B1  RES  49.9 1% CHIP  pkg 0402  page 21 : 1 = PVCCIO_CPU0 ; 2 = SVID_ALERT1_CPU0_R_N
R6B2  RES  100.0 1% CHIP  pkg 0402  page 21 : 1 = PVCCIO_CPU0 ; 2 = SVID_DIO1_CPU0_R
R6B3  RES  221 1.0% CHIP  pkg 0402  page 21 : 1 = SVID_ALERT1_CPU0_N ; 2 = SVID_ALERT1_CPU0_R_N
R6B4  RES  0.0 5% CHIP  pkg 0402  page 21 : 1 = SVID_DIO1_CPU0 ; 2 = SVID_DIO1_CPU0_R
R6B5  RES  0.0 5% CHIP  pkg 0402  page 21 : 1 = SVID_CLK1_CPU0 ; 2 = SVID_CLK1_CPU0_R
R6D1  RES  100.0 1% CHIP  pkg 0402  page 21 : 1 = A_CPU0_DEF_RCOMP2 ; 2 = GND
R6D2  RES  49.9 1% CHIP  pkg 0402  page 21 : 1 = A_CPU0_MCP01_RBIAS ; 2 = GND
R6D5  RES  49.9 1% CHIP  pkg 0402  page 90 : 1 = PD_CPU0_TEST12 ; 2 = GND
R6D6  RES  240 1.0% EMPTY  pkg 0402  page 90 : 1 = GND ; 2 = PD_CPU0_TXT_PLTEN
R6D7  RES  240 1.0% EMPTY  pkg 0402  page 90 : 1 = PVCCIO_CPU0 ; 2 = H_CPU0_BMCINIT
R6D8  RES  49.9 1% CHIP  pkg 0402  page 96 : 1 = PVCCIO_CPU0 ; 2 = PWRGD_CPU0_G
R6D9  RES  150.0 1% CHIP  pkg 0402  page 92 : 1 = PVCCIO_CPU0 ; 2 = H_CPU0_MSMI_G_N
R6D10  RES  240 1.0% EMPTY  pkg 0402  page 90 : 1 = PVCCIO_CPU0 ; 2 = PU_CPU0_SOCKET_ID_1
R6D11  RES  49.9 1% CHIP  pkg 0402  page 21 : 1 = A_CPU0_UPI01_RBIAS ; 2 = GND
R6D12  RES  49.9 1% CHIP  pkg 0402  page 96 : 1 = PVCCIO_CPU0 ; 2 = RST_CPU0_G_N
R6D13  RES  240 1.0% EMPTY  pkg 0402  page 90 : 1 = PVCCIO_CPU0 ; 2 = PU_CPU0_SAFE_MODE_BOOT
R6D14  RES  240 1.0% EMPTY  pkg 0402  page 90 : 1 = GND ; 2 = PD_CPU0_EAR_N
R6D15  RES  240 1.0% EMPTY  pkg 0402  page 90 : 1 = PVCCIO_CPU0 ; 2 = PU_CPU0_SOCKET_ID_0
R6D16  RES  0.0 5% EMPTY  pkg 0402  page 156 : 1 = FM_CPU_BMC_INIT ; 2 = H_CPU0_BMCINIT
R6F1  RES  49.9 1% CHIP  pkg 0402  page 89 : 1 = IRQ_DIMM_SAVE_N ; 2 = FM_ADR_COMPLETE_DEF_N
R6F2  RES  49.9 1% CHIP  pkg 0402  page 89 : 1 = FM_ADR_COMPLETE_CPU1_N ; 2 = FM_ADR_COMPLETE_KLM_N
R6F3  RES  10.0K 1% CHIP  pkg 0402  page 89 : 1 = PVPP_ABC ; 2 = IRQ_DIMM_SAVE_N
R6F4  RES  49.9 1% CHIP  pkg 0402  page 89 : 1 = IRQ_DIMM_SAVE_N ; 2 = FM_ADR_COMPLETE_ABC_N
R6F5  RES  49.9 1% CHIP  pkg 0402  page 89 : 1 = FM_ADR_COMPLETE_CPU1_N ; 2 = FM_ADR_COMPLETE_GHJ_N
R6F6  RES  0.0 5% EMPTY  pkg 0402  page 104 : 1 = CLK_322M_156M_CPU0_OSC_VRM_DN ; 2 = CLK_156M_OSC_CPU0_HFI_DN
R6F7  RES  0.0 5% CHIP  pkg 0402  page 104 : 1 = CLK_156M_OSC_BRD_CPU0_DN ; 2 = CLK_156M_OSC_CPU0_HFI_DN
R6F8  RES  0.0 5% EMPTY  pkg 0402  page 104 : 1 = CLK_322M_156M_CPU0_OSC_VRM_DP ; 2 = CLK_156M_OSC_CPU0_HFI_DP
R6F9  RES  0.0 5% CHIP  pkg 0402  page 104 : 1 = CLK_156M_OSC_BRD_CPU0_DP ; 2 = CLK_156M_OSC_CPU0_HFI_DP
R6F10  RES  0.0 5% EMPTY  pkg 0402  page 104 : 1 = CLK_322M_156M_CPU0_OSC_VRM_DN ; 2 = CLK_322M_OSC_CPU0_RC_DN
R6F11  RES  0.0 5% EMPTY  pkg 0402  page 104 : 1 = CLK_322M_156M_CPU0_OSC_VRM_DP ; 2 = CLK_322M_OSC_CPU0_RC_DP
R6L1  RES  1.00K 1% CHIP  pkg 0402  page 98 : 1 = M_F_VREF ; 2 = GND
R6L2  RES  1.00K 1% CHIP  pkg 0402  page 98 : 1 = PVDDQ_DEF ; 2 = M_F_VREF
R6L3  RES  2 1.0% CHIP  pkg 0402  page 98 : 1 = M_F_CPU_VREF ; 2 = M_F_VREF
R6L4  RES  1.0M 1% EMPTY  pkg 0402  page 222 : 1 = P3V3 ; 2 = FM_PVTT_DEF_EN_R
